# SCM (Grand Teton) — schematic netlist excerpt (pin names and nets, part order shuffled) for the footprints in the layout excerpt that follows; sources: Cadence DE-HDL packaged netlist, KiCad conversion of 12092022_DA0F0TMDCD0_F0T_Management_Board_D_brd_V3_OCP.brd

OSC2  OSC4_7X25000018  25MHZ MISC  pkg X_7X  page 34
  OE  = PU_25M_FPGA_CLK_EN
  GND  = GND
  \out\  = CLK_25M_OSC_FPGA_R
  VDD  = P3V3_AUX

U11  BAT54C  IC  pkg SOT23_123  page 27
  B  = FM_BMC_ONCTL_R_N
  A  = UART_BMC_5_TXD_R
  C  = FM_BMC_DISABLE

(kicad_pcb
	(version 20260206)
	(generator "pcbnew")
	(generator_version "10.0")
	(general
		(thickness 1.6)
		(legacy_teardrops no)
	)
	(paper "A4")
	(title_block
		(title "12092022_DA0F0TMDCD0_F0T_Management_Board_D_brd_V3_OCP.brd")
		(comment 1 "Grand Teton / footprints 1016-1017 of 1440")
	)
	(layers
		(0 "F.Cu" signal "TOP")
		(4 "In1.Cu" signal "GND")
		(6 "In2.Cu" signal "IN1")
		(8 "In3.Cu" signal "GND1")
		(10 "In4.Cu" signal "IN2")
		(12 "In5.Cu" signal "VCC")
		(14 "In6.Cu" signal "VCC1")
		(16 "In7.Cu" signal "IN3")
		(18 "In8.Cu" signal "GND2")
		(20 "In9.Cu" signal "IN4")
		(22 "In10.Cu" signal "GND3")
		(2 "B.Cu" signal "BOTTOM")
		(9 "F.Adhes" user "F.Adhesive")
		(11 "B.Adhes" user "B.Adhesive")
		(13 "F.Paste" user "Package Geometry/Pastemask Top")
		(15 "B.Paste" user "Package Geometry/Pastemask Bottom")
		(5 "F.SilkS" user "Ref Des/Silkscreen Top")
		(7 "B.SilkS" user "Ref Des/Silkscreen Bottom")
		(1 "F.Mask" user "Board Geometry/Soldermask Top")
		(3 "B.Mask" user "Board Geometry/Soldermask Bottom")
		(17 "Dwgs.User" user "User.Drawings")
		(19 "Cmts.User" user "User.Comments")
		(21 "Eco1.User" user "User.Eco1")
		(23 "Eco2.User" user "User.Eco2")
		(25 "Edge.Cuts" user "Board Geometry/Outline")
		(27 "Margin" user)
		(31 "F.CrtYd" user "Package Geometry/Place Bound Top")
		(29 "B.CrtYd" user "Package Geometry/Place Bound Bottom")
		(35 "F.Fab" user "Ref Des/Assembly Top")
		(33 "B.Fab" user "Ref Des/Assembly Bottom")
	)
	(footprint ""
		(layer "B.Cu")
		(at 20.80133 -77.50683 90)
		(property "Reference" "OSC2"
			(at -2.07518 2.46507 0)
			(unlocked yes)
			(layer "B.SilkS")
			(effects
				(font
					(size 0.635 0.4064)
					(thickness 0.1524)
				)
				(justify left mirror)
			)
		)
		(property "Value" ""
			(at 0 0 90)
			(layer "B.Fab")
			(effects
				(font
					(size 1.27 1.27)
				)
				(justify mirror)
			)
		)
		(duplicate_pad_numbers_are_jumpers no)
		(fp_line
			(start 1.397 -1.761236)
			(end 1.397 1.761236)
			(stroke
				(width 0.1524)
				(type default)
			)
			(layer "B.SilkS")
		)
		(fp_line
			(start -1.397 -1.761236)
			(end 1.397 -1.761236)
			(stroke
				(width 0.1524)
				(type default)
			)
			(layer "B.SilkS")
		)
		(fp_line
			(start 1.397 1.761236)
			(end -1.397 1.761236)
			(stroke
				(width 0.1524)
				(type default)
			)
			(layer "B.SilkS")
		)
		(fp_line
			(start -1.397 1.761236)
			(end -1.397 -1.761236)
			(stroke
				(width 0.1524)
				(type default)
			)
			(layer "B.SilkS")
		)
		(fp_poly
			(pts
				(xy 1.965706 -0.825246) (xy 3.043428 -0.46609) (xy 2.324862 0.252476)
			)
			(stroke
				(width 0)
				(type default)
			)
			(fill yes)
			(layer "B.SilkS")
		)
		(fp_line
			(start 1.299972 -1.649984)
			(end -1.299972 -1.649984)
			(stroke
				(width 0.1)
				(type default)
			)
			(layer "B.Fab")
		)
		(fp_line
			(start -1.299972 -1.649984)
			(end -1.299972 1.649984)
			(stroke
				(width 0.1)
				(type default)
			)
			(layer "B.Fab")
		)
		(fp_line
			(start 1.299972 1.649984)
			(end 1.299972 -1.649984)
			(stroke
				(width 0.1)
				(type default)
			)
			(layer "B.Fab")
		)
		(fp_line
			(start -1.299972 1.649984)
			(end 1.299972 1.649984)
			(stroke
				(width 0.1)
				(type default)
			)
			(layer "B.Fab")
		)
		(fp_poly
			(pts
				(xy 1.694688 -1.050036) (xy 2.710688 -1.558036) (xy 2.710688 -0.542036)
			)
			(stroke
				(width 0)
				(type default)
			)
			(fill yes)
			(layer "B.Fab")
		)
		(pad "1" smd rect
			(at 0.824992 -1.050036 270)
			(size 0.8636 1.1684)
			(layers "B.Cu" "B.Mask" "B.Paste")
			(net "PU_25M_FPGA_CLK_EN")
		)
		(pad "2" smd rect
			(at 0.824992 1.050036 270)
			(size 0.8636 1.1684)
			(layers "B.Cu" "B.Mask" "B.Paste")
			(net "GND")
		)
		(pad "3" smd rect
			(at -0.824992 1.050036 270)
			(size 0.8636 1.1684)
			(layers "B.Cu" "B.Mask" "B.Paste")
			(net "CLK_25M_OSC_FPGA_R")
		)
		(pad "4" smd rect
			(at -0.824992 -1.050036 270)
			(size 0.8636 1.1684)
			(layers "B.Cu" "B.Mask" "B.Paste")
			(net "P3V3_AUX")
		)
	)
	(footprint ""
		(layer "B.Cu")
		(at 42.183558 -84.33816 90)
		(property "Reference" "U11"
			(at 0.26924 2.303272 270)
			(unlocked yes)
			(layer "B.SilkS")
			(effects
				(font
					(size 0.7874 0.5842)
					(thickness 0.1524)
				)
				(justify mirror)
			)
		)
		(property "Value" ""
			(at 0 0 90)
			(layer "B.Fab")
			(effects
				(font
					(size 1.27 1.27)
				)
				(justify mirror)
			)
		)
		(duplicate_pad_numbers_are_jumpers no)
		(fp_line
			(start 1.905 -1.651)
			(end -1.905 -1.651)
			(stroke
				(width 0.1524)
				(type default)
			)
			(layer "B.SilkS")
		)
		(fp_line
			(start -1.905 -1.651)
			(end -1.905 1.651)
			(stroke
				(width 0.1524)
				(type default)
			)
			(layer "B.SilkS")
		)
		(fp_line
			(start 1.905 1.651)
			(end 1.905 -1.651)
			(stroke
				(width 0.1524)
				(type default)
			)
			(layer "B.SilkS")
		)
		(fp_line
			(start -1.905 1.651)
			(end 1.905 1.651)
			(stroke
				(width 0.1524)
				(type default)
			)
			(layer "B.SilkS")
		)
		(fp_line
			(start 0.649986 -1.524)
			(end -0.6985 -1.524)
			(stroke
				(width 0.1)
				(type default)
			)
			(layer "B.Fab")
		)
		(fp_line
			(start -0.6985 -1.524)
			(end -0.6985 -0.219964)
			(stroke
				(width 0.1)
				(type default)
			)
			(layer "B.Fab")
		)
		(fp_line
			(start 1.249934 -1.169924)
			(end 0.649986 -1.169924)
			(stroke
				(width 0.1)
				(type default)
			)
			(layer "B.Fab")
		)
		(fp_line
			(start 0.649986 -1.169924)
			(end 0.649986 -1.524)
			(stroke
				(width 0.1)
				(type default)
			)
			(layer "B.Fab")
		)
		(fp_line
			(start 1.249934 -0.729996)
			(end 1.249934 -1.169924)
			(stroke
				(width 0.1)
				(type default)
			)
			(layer "B.Fab")
		)
		(fp_line
			(start 0.6985 -0.729996)
			(end 1.249934 -0.729996)
			(stroke
				(width 0.1)
				(type default)
			)
			(layer "B.Fab")
		)
		(fp_line
			(start -0.6985 -0.219964)
			(end -1.249934 -0.219964)
			(stroke
				(width 0.1)
				(type default)
			)
			(layer "B.Fab")
		)
		(fp_line
			(start -1.249934 -0.219964)
			(end -1.249934 0.219964)
			(stroke
				(width 0.1)
				(type default)
			)
			(layer "B.Fab")
		)
		(fp_line
			(start -0.6985 0.219964)
			(end -0.6985 1.524)
			(stroke
				(width 0.1)
				(type default)
			)
			(layer "B.Fab")
		)
		(fp_line
			(start -1.249934 0.219964)
			(end -0.6985 0.219964)
			(stroke
				(width 0.1)
				(type default)
			)
			(layer "B.Fab")
		)
		(fp_line
			(start 1.249934 0.729996)
			(end 0.6985 0.729996)
			(stroke
				(width 0.1)
				(type default)
			)
			(layer "B.Fab")
		)
		(fp_line
			(start 0.6985 0.729996)
			(end 0.6985 -0.729996)
			(stroke
				(width 0.1)
				(type default)
			)
			(layer "B.Fab")
		)
		(fp_line
			(start 1.249934 1.169924)
			(end 1.249934 0.729996)
			(stroke
				(width 0.1)
				(type default)
			)
			(layer "B.Fab")
		)
		(fp_line
			(start 0.649986 1.169924)
			(end 1.249934 1.169924)
			(stroke
				(width 0.1)
				(type default)
			)
			(layer "B.Fab")
		)
		(fp_line
			(start 0.649986 1.524)
			(end 0.649986 1.169924)
			(stroke
				(width 0.1)
				(type default)
			)
			(layer "B.Fab")
		)
		(fp_line
			(start -0.6985 1.524)
			(end 0.649986 1.524)
			(stroke
				(width 0.1)
				(type default)
			)
			(layer "B.Fab")
		)
		(pad "1" smd rect
			(at 1.1176 -1.016)
			(size 1.016 1.27)
			(layers "B.Cu" "B.Mask" "B.Paste")
			(net "FM_BMC_ONCTL_R_N")
		)
		(pad "2" smd rect
			(at 1.1176 1.016)
			(size 1.016 1.27)
			(layers "B.Cu" "B.Mask" "B.Paste")
			(net "UART_BMC_5_TXD_R")
		)
		(pad "3" smd rect
			(at -1.1176 0)
			(size 1.016 1.27)
			(layers "B.Cu" "B.Mask" "B.Paste")
			(net "FM_BMC_DISABLE")
		)
	)
)
